(kicad_pcb
	(version 20260206)
	(generator "pcbnew")
	(generator_version "10.0")
	(general
		(thickness 1.6)
		(legacy_teardrops no)
	)
	(paper "A4")
	(title_block
		(title "timecard-production-celestica-r4006 — R4006-B0001-02_R01.brd")
		(comment 1 "Time Appliance Project (Time Card) / footprints 945-949 of 1113")
	)
	(layers
		(0 "F.Cu" signal "TOP")
		(4 "In1.Cu" signal "L02_GND1")
		(6 "In2.Cu" signal "L03_SIG1")
		(8 "In3.Cu" signal "L04_GND2")
		(10 "In4.Cu" signal "L05_VCC1")
		(12 "In5.Cu" signal "L06_VCC2")
		(14 "In6.Cu" signal "L07_GND3")
		(16 "In7.Cu" signal "L08_SIG2")
		(18 "In8.Cu" signal "L09_GND4")
		(2 "B.Cu" signal "BOTTOM")
		(9 "F.Adhes" user "F.Adhesive")
		(11 "B.Adhes" user "B.Adhesive")
		(13 "F.Paste" user "Package Geometry/Pastemask Top")
		(15 "B.Paste" user "Package Geometry/Pastemask Bottom")
		(5 "F.SilkS" user "Ref Des/Silkscreen Top")
		(7 "B.SilkS" user "Ref Des/Silkscreen Bottom")
		(1 "F.Mask" user "Board Geometry/Soldermask Top")
		(3 "B.Mask" user "Board Geometry/Soldermask Bottom")
		(17 "Dwgs.User" user "User.Drawings")
		(19 "Cmts.User" user "User.Comments")
		(21 "Eco1.User" user "User.Eco1")
		(23 "Eco2.User" user "User.Eco2")
		(25 "Edge.Cuts" user "Board Geometry/Outline")
		(27 "Margin" user)
		(31 "F.CrtYd" user "Package Geometry/Place Bound Top")
		(29 "B.CrtYd" user "Package Geometry/Place Bound Bottom")
		(35 "F.Fab" user "Ref Des/Assembly Top")
		(33 "B.Fab" user "Ref Des/Assembly Bottom")
	)
	(footprint ""
		(layer "B.Cu")
		(at 162.56 -24.511 180)
		(property "Reference" "R411"
			(at 0.381 -1.43637 0)
			(unlocked yes)
			(layer "B.SilkS")
			(effects
				(font
					(size 0.7874 0.5842)
					(thickness 0.1524)
				)
				(justify mirror)
			)
		)
		(property "Value" "VAL*"
			(at -0.02032 2.13233 180)
			(unlocked yes)
			(layer "B.Fab")
			(hide yes)
			(effects
				(font
					(size 0.7874 0.5842)
					(thickness 0.1524)
				)
				(justify mirror)
			)
		)
		(property "Tolerance" "TOL*"
			(at -0.044704 3.05435 180)
			(unlocked yes)
			(layer "Cmts.User")
			(hide yes)
			(effects
				(font
					(size 0.7874 0.5842)
					(thickness 0.1524)
				)
				(justify mirror)
			)
		)
		(property "User Part Number" "PARTNUM*"
			(at -0.02032 4.024884 180)
			(unlocked yes)
			(layer "Cmts.User")
			(hide yes)
			(effects
				(font
					(size 0.7874 0.5842)
					(thickness 0.1524)
				)
				(justify mirror)
			)
		)
		(property "Device Type" "RESISTOR-G155-11001-01,1KOHM,1%"
			(at -0.008382 1.210564 180)
			(unlocked yes)
			(layer "B.Fab")
			(hide yes)
			(effects
				(font
					(size 0.7874 0.5842)
					(thickness 0.1524)
				)
				(justify mirror)
			)
		)
		(duplicate_pad_numbers_are_jumpers no)
		(fp_line
			(start 1.143 0.5588)
			(end -1.143 0.5588)
			(stroke
				(width 0.1)
				(type default)
			)
			(layer "B.SilkS")
		)
		(fp_line
			(start 1.143 -0.5588)
			(end 1.143 0.5588)
			(stroke
				(width 0.1)
				(type default)
			)
			(layer "B.SilkS")
		)
		(fp_line
			(start -1.143 0.5588)
			(end -1.143 -0.5588)
			(stroke
				(width 0.1)
				(type default)
			)
			(layer "B.SilkS")
		)
		(fp_line
			(start -1.143 -0.5588)
			(end 1.143 -0.5588)
			(stroke
				(width 0.1)
				(type default)
			)
			(layer "B.SilkS")
		)
		(fp_rect
			(start 1.143 0.5588)
			(end -1.143 -0.5588)
			(stroke
				(width 0)
				(type default)
			)
			(fill no)
			(layer "B.CrtYd")
		)
		(fp_line
			(start 0.508 0.3048)
			(end -0.508 0.3048)
			(stroke
				(width 0.1)
				(type default)
			)
			(layer "B.Fab")
		)
		(fp_line
			(start 0.508 -0.3048)
			(end 0.508 0.3048)
			(stroke
				(width 0.1)
				(type default)
			)
			(layer "B.Fab")
		)
		(fp_line
			(start -0.508 0.3048)
			(end -0.508 -0.3048)
			(stroke
				(width 0.1)
				(type default)
			)
			(layer "B.Fab")
		)
		(fp_line
			(start -0.508 -0.3048)
			(end 0.508 -0.3048)
			(stroke
				(width 0.1)
				(type default)
			)
			(layer "B.Fab")
		)
		(pad "1" smd rect
			(at 0.5334 0)
			(size 0.7112 0.6096)
			(layers "B.Cu" "B.Mask" "B.Paste")
			(net "UNNAMED_6_LM75BDPTSSOP8_I81_A2")
		)
		(pad "2" smd rect
			(at -0.5334 0)
			(size 0.7112 0.6096)
			(layers "B.Cu" "B.Mask" "B.Paste")
			(net "SG")
		)
		(zone
			(layer "B.Cu")
			(hatch none 0.5)
			(connect_pads
				(clearance 0)
			)
			(min_thickness 0.25)
			(keepout
				(tracks allowed)
				(vias not_allowed)
				(pads allowed)
				(copperpour not_allowed)
				(footprints allowed)
			)
			(placement
				(enabled no)
				(sheetname "")
			)
			(fill
				(thermal_gap 0.5)
				(thermal_bridge_width 0.5)
				(island_removal_mode 0)
			)
			(polygon
				(pts
					(xy 162.4838 -24.8158) (xy 162.4838 -24.2062) (xy 162.6362 -24.2062) (xy 162.6362 -24.8158)
				)
			)
		)
		(zone
			(layer "B.Cu")
			(hatch none 0.5)
			(connect_pads
				(clearance 0)
			)
			(min_thickness 0.25)
			(keepout
				(tracks not_allowed)
				(vias allowed)
				(pads allowed)
				(copperpour not_allowed)
				(footprints allowed)
			)
			(placement
				(enabled no)
				(sheetname "")
			)
			(fill
				(thermal_gap 0.5)
				(thermal_bridge_width 0.5)
				(island_removal_mode 0)
			)
			(polygon
				(pts
					(xy 162.4838 -24.8158) (xy 162.4838 -24.2062) (xy 162.6362 -24.2062) (xy 162.6362 -24.8158)
				)
			)
		)
	)
	(footprint ""
		(layer "B.Cu")
		(at 153.0858 -107.696 90)
		(property "Reference" "R279"
			(at 0.508 -2.37617 270)
			(unlocked yes)
			(layer "B.SilkS")
			(effects
				(font
					(size 0.7874 0.5842)
					(thickness 0.1524)
				)
				(justify mirror)
			)
		)
		(property "Value" "VAL*"
			(at -0.02032 2.13233 90)
			(unlocked yes)
			(layer "B.Fab")
			(hide yes)
			(effects
				(font
					(size 0.7874 0.5842)
					(thickness 0.1524)
				)
				(justify mirror)
			)
		)
		(property "Tolerance" "TOL*"
			(at -0.044704 3.05435 90)
			(unlocked yes)
			(layer "Cmts.User")
			(hide yes)
			(effects
				(font
					(size 0.7874 0.5842)
					(thickness 0.1524)
				)
				(justify mirror)
			)
		)
		(property "User Part Number" "PARTNUM*"
			(at -0.02032 4.024884 90)
			(unlocked yes)
			(layer "Cmts.User")
			(hide yes)
			(effects
				(font
					(size 0.7874 0.5842)
					(thickness 0.1524)
				)
				(justify mirror)
			)
		)
		(property "Device Type" "RESISTOR-G155-13300-01,330OHM,A"
			(at -0.008382 1.210564 90)
			(unlocked yes)
			(layer "B.Fab")
			(hide yes)
			(effects
				(font
					(size 0.7874 0.5842)
					(thickness 0.1524)
				)
				(justify mirror)
			)
		)
		(duplicate_pad_numbers_are_jumpers no)
		(fp_line
			(start 1.143 -0.5588)
			(end 1.143 0.5588)
			(stroke
				(width 0.1)
				(type default)
			)
			(layer "B.SilkS")
		)
		(fp_line
			(start -1.143 -0.5588)
			(end 1.143 -0.5588)
			(stroke
				(width 0.1)
				(type default)
			)
			(layer "B.SilkS")
		)
		(fp_line
			(start 1.143 0.5588)
			(end -1.143 0.5588)
			(stroke
				(width 0.1)
				(type default)
			)
			(layer "B.SilkS")
		)
		(fp_line
			(start -1.143 0.5588)
			(end -1.143 -0.5588)
			(stroke
				(width 0.1)
				(type default)
			)
			(layer "B.SilkS")
		)
		(fp_rect
			(start -1.143 -0.5588)
			(end 1.143 0.5588)
			(stroke
				(width 0)
				(type default)
			)
			(fill no)
			(layer "B.CrtYd")
		)
		(fp_line
			(start 0.508 -0.3048)
			(end 0.508 0.3048)
			(stroke
				(width 0.1)
				(type default)
			)
			(layer "B.Fab")
		)
		(fp_line
			(start -0.508 -0.3048)
			(end 0.508 -0.3048)
			(stroke
				(width 0.1)
				(type default)
			)
			(layer "B.Fab")
		)
		(fp_line
			(start 0.508 0.3048)
			(end -0.508 0.3048)
			(stroke
				(width 0.1)
				(type default)
			)
			(layer "B.Fab")
		)
		(fp_line
			(start -0.508 0.3048)
			(end -0.508 -0.3048)
			(stroke
				(width 0.1)
				(type default)
			)
			(layer "B.Fab")
		)
		(pad "1" smd rect
			(at 0.5334 0 270)
			(size 0.7112 0.6096)
			(layers "B.Cu" "B.Mask" "B.Paste")
			(net "UNNAMED_14_OPTICAL_I138_A")
		)
		(pad "2" smd rect
			(at -0.5334 0 270)
			(size 0.7112 0.6096)
			(layers "B.Cu" "B.Mask" "B.Paste")
			(net "XP3R3V_FPGA")
		)
		(zone
			(layer "B.Cu")
			(hatch none 0.5)
			(connect_pads
				(clearance 0)
			)
			(min_thickness 0.25)
			(keepout
				(tracks allowed)
				(vias not_allowed)
				(pads allowed)
				(copperpour not_allowed)
				(footprints allowed)
			)
			(placement
				(enabled no)
				(sheetname "")
			)
			(fill
				(thermal_gap 0.5)
				(thermal_bridge_width 0.5)
				(island_removal_mode 0)
			)
			(polygon
				(pts
					(xy 152.781 -107.6198) (xy 153.3906 -107.6198) (xy 153.3906 -107.7722) (xy 152.781 -107.7722)
				)
			)
		)
	)
	(footprint ""
		(layer "B.Cu")
		(at 87.376 -56.134)
		(property "Reference" "R76"
			(at 1.778 3.08737 0)
			(unlocked yes)
			(layer "B.SilkS")
			(effects
				(font
					(size 0.7874 0.5842)
					(thickness 0.1524)
				)
				(justify mirror)
			)
		)
		(property "Value" "VAL*"
			(at -0.02032 2.13233 0)
			(unlocked yes)
			(layer "B.Fab")
			(hide yes)
			(effects
				(font
					(size 0.7874 0.5842)
					(thickness 0.1524)
				)
				(justify mirror)
			)
		)
		(property "Device Type" "RESISTOR-G155-133R0-01,33OHM,1%"
			(at -0.008382 1.210564 0)
			(unlocked yes)
			(layer "B.Fab")
			(hide yes)
			(effects
				(font
					(size 0.7874 0.5842)
					(thickness 0.1524)
				)
				(justify mirror)
			)
		)
		(property "User Part Number" "PARTNUM*"
			(at -0.02032 4.024884 0)
			(unlocked yes)
			(layer "Cmts.User")
			(hide yes)
			(effects
				(font
					(size 0.7874 0.5842)
					(thickness 0.1524)
				)
				(justify mirror)
			)
		)
		(property "Tolerance" "TOL*"
			(at -0.044704 3.05435 0)
			(unlocked yes)
			(layer "Cmts.User")
			(hide yes)
			(effects
				(font
					(size 0.7874 0.5842)
					(thickness 0.1524)
				)
				(justify mirror)
			)
		)
		(duplicate_pad_numbers_are_jumpers no)
		(fp_line
			(start -1.143 -0.5588)
			(end 1.143 -0.5588)
			(stroke
				(width 0.1)
				(type default)
			)
			(layer "B.SilkS")
		)
		(fp_line
			(start -1.143 0.5588)
			(end -1.143 -0.5588)
			(stroke
				(width 0.1)
				(type default)
			)
			(layer "B.SilkS")
		)
		(fp_line
			(start 1.143 -0.5588)
			(end 1.143 0.5588)
			(stroke
				(width 0.1)
				(type default)
			)
			(layer "B.SilkS")
		)
		(fp_line
			(start 1.143 0.5588)
			(end -1.143 0.5588)
			(stroke
				(width 0.1)
				(type default)
			)
			(layer "B.SilkS")
		)
		(fp_rect
			(start 1.143 -0.5588)
			(end -1.143 0.5588)
			(stroke
				(width 0)
				(type default)
			)
			(fill no)
			(layer "B.CrtYd")
		)
		(fp_line
			(start -0.508 -0.3048)
			(end 0.508 -0.3048)
			(stroke
				(width 0.1)
				(type default)
			)
			(layer "B.Fab")
		)
		(fp_line
			(start -0.508 0.3048)
			(end -0.508 -0.3048)
			(stroke
				(width 0.1)
				(type default)
			)
			(layer "B.Fab")
		)
		(fp_line
			(start 0.508 -0.3048)
			(end 0.508 0.3048)
			(stroke
				(width 0.1)
				(type default)
			)
			(layer "B.Fab")
		)
		(fp_line
			(start 0.508 0.3048)
			(end -0.508 0.3048)
			(stroke
				(width 0.1)
				(type default)
			)
			(layer "B.Fab")
		)
		(pad "1" smd rect
			(at 0.5334 0 180)
			(size 0.7112 0.6096)
			(layers "B.Cu" "B.Mask" "B.Paste")
			(net "BNO080_I2C_SDA")
		)
		(pad "2" smd rect
			(at -0.5334 0 180)
			(size 0.7112 0.6096)
			(layers "B.Cu" "B.Mask" "B.Paste")
			(net "R_BNO080_I2C_SDA")
		)
		(zone
			(layer "B.Cu")
			(hatch none 0.5)
			(connect_pads
				(clearance 0)
			)
			(min_thickness 0.25)
			(keepout
				(tracks allowed)
				(vias not_allowed)
				(pads allowed)
				(copperpour not_allowed)
				(footprints allowed)
			)
			(placement
				(enabled no)
				(sheetname "")
			)
			(fill
				(thermal_gap 0.5)
				(thermal_bridge_width 0.5)
				(island_removal_mode 0)
			)
			(polygon
				(pts
					(xy 87.4522 -56.4388) (xy 87.2998 -56.4388) (xy 87.2998 -55.8292) (xy 87.4522 -55.8292)
				)
			)
		)
	)
	(footprint ""
		(layer "B.Cu")
		(at 115.443 -70.993)
		(property "Reference" "R260"
			(at -0.127 2.19837 0)
			(unlocked yes)
			(layer "B.SilkS")
			(effects
				(font
					(size 0.7874 0.5842)
					(thickness 0.1524)
				)
				(justify mirror)
			)
		)
		(property "Value" "VAL*"
			(at -0.02032 2.13233 0)
			(unlocked yes)
			(layer "B.Fab")
			(hide yes)
			(effects
				(font
					(size 0.7874 0.5842)
					(thickness 0.1524)
				)
				(justify mirror)
			)
		)
		(property "Tolerance" "TOL*"
			(at -0.044704 3.05435 0)
			(unlocked yes)
			(layer "Cmts.User")
			(hide yes)
			(effects
				(font
					(size 0.7874 0.5842)
					(thickness 0.1524)
				)
				(justify mirror)
			)
		)
		(property "User Part Number" "PARTNUM*"
			(at -0.02032 4.024884 0)
			(unlocked yes)
			(layer "Cmts.User")
			(hide yes)
			(effects
				(font
					(size 0.7874 0.5842)
					(thickness 0.1524)
				)
				(justify mirror)
			)
		)
		(property "Device Type" "RESISTOR-G155-11001-01,1KOHM,1%"
			(at -0.008382 1.210564 0)
			(unlocked yes)
			(layer "B.Fab")
			(hide yes)
			(effects
				(font
					(size 0.7874 0.5842)
					(thickness 0.1524)
				)
				(justify mirror)
			)
		)
		(duplicate_pad_numbers_are_jumpers no)
		(fp_line
			(start -1.143 -0.5588)
			(end 1.143 -0.5588)
			(stroke
				(width 0.1)
				(type default)
			)
			(layer "B.SilkS")
		)
		(fp_line
			(start -1.143 0.5588)
			(end -1.143 -0.5588)
			(stroke
				(width 0.1)
				(type default)
			)
			(layer "B.SilkS")
		)
		(fp_line
			(start 1.143 -0.5588)
			(end 1.143 0.5588)
			(stroke
				(width 0.1)
				(type default)
			)
			(layer "B.SilkS")
		)
		(fp_line
			(start 1.143 0.5588)
			(end -1.143 0.5588)
			(stroke
				(width 0.1)
				(type default)
			)
			(layer "B.SilkS")
		)
		(fp_rect
			(start -1.143 0.5588)
			(end 1.143 -0.5588)
			(stroke
				(width 0)
				(type default)
			)
			(fill no)
			(layer "B.CrtYd")
		)
		(fp_line
			(start -0.508 -0.3048)
			(end 0.508 -0.3048)
			(stroke
				(width 0.1)
				(type default)
			)
			(layer "B.Fab")
		)
		(fp_line
			(start -0.508 0.3048)
			(end -0.508 -0.3048)
			(stroke
				(width 0.1)
				(type default)
			)
			(layer "B.Fab")
		)
		(fp_line
			(start 0.508 -0.3048)
			(end 0.508 0.3048)
			(stroke
				(width 0.1)
				(type default)
			)
			(layer "B.Fab")
		)
		(fp_line
			(start 0.508 0.3048)
			(end -0.508 0.3048)
			(stroke
				(width 0.1)
				(type default)
			)
			(layer "B.Fab")
		)
		(pad "1" smd rect
			(at 0.5334 0 180)
			(size 0.7112 0.6096)
			(layers "B.Cu" "B.Mask" "B.Paste")
			(net "XP3R3V")
		)
		(pad "2" smd rect
			(at -0.5334 0 180)
			(size 0.7112 0.6096)
			(layers "B.Cu" "B.Mask" "B.Paste")
			(net "XP3R3V_FPGA_EN_R")
		)
		(zone
			(layer "B.Cu")
			(hatch none 0.5)
			(connect_pads
				(clearance 0)
			)
			(min_thickness 0.25)
			(keepout
				(tracks allowed)
				(vias not_allowed)
				(pads allowed)
				(copperpour not_allowed)
				(footprints allowed)
			)
			(placement
				(enabled no)
				(sheetname "")
			)
			(fill
				(thermal_gap 0.5)
				(thermal_bridge_width 0.5)
				(island_removal_mode 0)
			)
			(polygon
				(pts
					(xy 115.3668 -70.6882) (xy 115.5192 -70.6882) (xy 115.5192 -71.2978) (xy 115.3668 -71.2978)
				)
			)
		)
	)
	(footprint ""
		(layer "B.Cu")
		(at 142.24 -59.563 -90)
		(property "Reference" "R249"
			(at -3.175 0.16637 270)
			(unlocked yes)
			(layer "B.SilkS")
			(effects
				(font
					(size 0.7874 0.5842)
					(thickness 0.1524)
				)
				(justify mirror)
			)
		)
		(property "Value" "VAL*"
			(at -0.02032 2.13233 270)
			(unlocked yes)
			(layer "B.Fab")
			(hide yes)
			(effects
				(font
					(size 0.7874 0.5842)
					(thickness 0.1524)
				)
				(justify mirror)
			)
		)
		(property "Device Type" "RESISTOR-G155-14701-01,4.7KOHMA"
			(at -0.008382 1.210564 270)
			(unlocked yes)
			(layer "B.Fab")
			(hide yes)
			(effects
				(font
					(size 0.7874 0.5842)
					(thickness 0.1524)
				)
				(justify mirror)
			)
		)
		(property "User Part Number" "PARTNUM*"
			(at -0.02032 4.024884 270)
			(unlocked yes)
			(layer "Cmts.User")
			(hide yes)
			(effects
				(font
					(size 0.7874 0.5842)
					(thickness 0.1524)
				)
				(justify mirror)
			)
		)
		(property "Tolerance" "TOL*"
			(at -0.044704 3.05435 270)
			(unlocked yes)
			(layer "Cmts.User")
			(hide yes)
			(effects
				(font
					(size 0.7874 0.5842)
					(thickness 0.1524)
				)
				(justify mirror)
			)
		)
		(duplicate_pad_numbers_are_jumpers no)
		(fp_line
			(start -1.143 0.5588)
			(end -1.143 -0.5588)
			(stroke
				(width 0.1)
				(type default)
			)
			(layer "B.SilkS")
		)
		(fp_line
			(start 1.143 0.5588)
			(end -1.143 0.5588)
			(stroke
				(width 0.1)
				(type default)
			)
			(layer "B.SilkS")
		)
		(fp_line
			(start -1.143 -0.5588)
			(end 1.143 -0.5588)
			(stroke
				(width 0.1)
				(type default)
			)
			(layer "B.SilkS")
		)
		(fp_line
			(start 1.143 -0.5588)
			(end 1.143 0.5588)
			(stroke
				(width 0.1)
				(type default)
			)
			(layer "B.SilkS")
		)
		(fp_rect
			(start 1.143 0.5588)
			(end -1.143 -0.5588)
			(stroke
				(width 0)
				(type default)
			)
			(fill no)
			(layer "B.CrtYd")
		)
		(fp_line
			(start -0.508 0.3048)
			(end -0.508 -0.3048)
			(stroke
				(width 0.1)
				(type default)
			)
			(layer "B.Fab")
		)
		(fp_line
			(start 0.508 0.3048)
			(end -0.508 0.3048)
			(stroke
				(width 0.1)
				(type default)
			)
			(layer "B.Fab")
		)
		(fp_line
			(start -0.508 -0.3048)
			(end 0.508 -0.3048)
			(stroke
				(width 0.1)
				(type default)
			)
			(layer "B.Fab")
		)
		(fp_line
			(start 0.508 -0.3048)
			(end 0.508 0.3048)
			(stroke
				(width 0.1)
				(type default)
			)
			(layer "B.Fab")
		)
		(pad "1" smd rect
			(at 0.5334 0 90)
			(size 0.7112 0.6096)
			(layers "B.Cu" "B.Mask" "B.Paste")
			(net "XP1R0V_COMP")
		)
		(pad "2" smd rect
			(at -0.5334 0 90)
			(size 0.7112 0.6096)
			(layers "B.Cu" "B.Mask" "B.Paste")
			(net "UNNAMED_523_CAPACITOR_I9_1")
		)
		(zone
			(layer "B.Cu")
			(hatch none 0.5)
			(connect_pads
				(clearance 0)
			)
			(min_thickness 0.25)
			(keepout
				(tracks allowed)
				(vias not_allowed)
				(pads allowed)
				(copperpour not_allowed)
				(footprints allowed)
			)
			(placement
				(enabled no)
				(sheetname "")
			)
			(fill
				(thermal_gap 0.5)
				(thermal_bridge_width 0.5)
				(island_removal_mode 0)
			)
			(polygon
				(pts
					(xy 141.9352 -59.4868) (xy 142.5448 -59.4868) (xy 142.5448 -59.6392) (xy 141.9352 -59.6392)
				)
			)
		)
	)
)
